(kicad_pcb
	(version 20221018)
	(generator pcbnew)
	(general
    (thickness 1.518)
  )
	(paper "A4")
	(title_block
    (title "Kria K26 Devboard")
    (date "2024-03-26")
    (rev "1.2.5")
    (comment 1 "www.antmicro.com")
    (comment 2 "Antmicro Ltd.")
		(comment 9 "footprints 110-117 of 660")
	)
	(layers
    (0 "F.Cu" mixed)
    (1 "In1.Cu" power)
    (2 "In2.Cu" mixed)
    (3 "In3.Cu" power)
    (4 "In4.Cu" mixed)
    (5 "In5.Cu" power)
    (6 "In6.Cu" mixed)
    (31 "B.Cu" power)
    (32 "B.Adhes" user "B.Adhesive")
    (33 "F.Adhes" user "F.Adhesive")
    (34 "B.Paste" user)
    (35 "F.Paste" user)
    (36 "B.SilkS" user "B.Silkscreen")
    (37 "F.SilkS" user "F.Silkscreen")
    (38 "B.Mask" user)
    (39 "F.Mask" user)
    (40 "Dwgs.User" user "User.Drawings")
    (41 "Cmts.User" user "User.Comments")
    (42 "Eco1.User" user "User.Eco1")
    (43 "Eco2.User" user "User.Eco2")
    (44 "Edge.Cuts" user)
    (45 "Margin" user)
    (46 "B.CrtYd" user "B.Courtyard")
    (47 "F.CrtYd" user "F.Courtyard")
    (48 "B.Fab" user)
    (49 "F.Fab" user)
  )
	(footprint "kria-k26-devboard-footprints:MSOP-8-1EP_3x3x1.1mm_P0.65mm" (layer "F.Cu")
    (at 83.38 122.05 180)
    (property "Author" "Antmicro")
    (property "License" "Apache-2.0")
    (property "MPN" "PI4MSD5V9540BUEX")
    (property "Manufacturer" "Diodes Incorporated")
    (property "Sheetfile" "camera.kicad_sch")
    (property "Sheetname" "Camera interface")
    (property "ki_description" "Multiplexer, 2 Channels, 1:2, 1.65 V to 5.5 V, MSOP-8")
    (property "ki_keywords" "SMT, MUX, IC, I2C")
    (attr smd)
    (fp_text reference "U10" (at 1.739822 -2.55) (layer "F.SilkS")
        (effects (font (size 0.7 0.7) (thickness 0.15)) (justify left bottom))
    )
    (fp_text value "PI4MSD5V9540B_MSOP" (at 0 2.7) (layer "F.Fab") hide
        (effects (font (size 0.7 0.7) (thickness 0.15)) (justify left bottom))
    )
    (fp_text user "License: Apache-2.0" (at -5.576 10.98) (layer "F.Fab") hide
        (effects (font (size 0.7 0.7) (thickness 0.15)) (justify right bottom))
    )
    (fp_text user "Author: Antmicro" (at -5.576 9.779) (layer "F.Fab") hide
        (effects (font (size 0.7 0.7) (thickness 0.15)) (justify right bottom))
    )
    (fp_text user "REF**" (at -5.576 7.379) (layer "F.Fab") hide
        (effects (font (size 0.7 0.7) (thickness 0.15)) (justify right bottom))
    )
    (fp_text user "${REFERENCE}" (at -5.576 8.579) (layer "F.Fab") hide
        (effects (font (size 0.7 0.7) (thickness 0.15)) (justify right bottom))
    )
    (fp_line (start -1.6 1.6) (end -1.6 1.298)
      (stroke (width 0.15) (type solid)) (layer "F.SilkS"))
    (fp_line (start -1.299 -1.601) (end -1.6 -1.302)
      (stroke (width 0.15) (type solid)) (layer "F.SilkS"))
    (fp_line (start -1.299 1.6) (end -1.6 1.6)
      (stroke (width 0.15) (type solid)) (layer "F.SilkS"))
    (fp_line (start 1.3 -1.601) (end 1.601 -1.601)
      (stroke (width 0.15) (type solid)) (layer "F.SilkS"))
    (fp_line (start 1.601 -1.601) (end 1.601 -1.302)
      (stroke (width 0.15) (type solid)) (layer "F.SilkS"))
    (fp_line (start 1.601 1.298) (end 1.601 1.6)
      (stroke (width 0.15) (type solid)) (layer "F.SilkS"))
    (fp_line (start 1.601 1.6) (end 1.3 1.6)
      (stroke (width 0.15) (type solid)) (layer "F.SilkS"))
    (fp_circle (center -2.1 -1.5) (end -2.05 -1.55)
      (stroke (width 0.15) (type solid)) (fill solid) (layer "F.SilkS"))
    (fp_line (start -3.179 -1.747) (end 3.171 -1.747)
      (stroke (width 0.05) (type solid)) (layer "F.CrtYd"))
    (fp_line (start -3.179 1.753) (end -3.179 -1.747)
      (stroke (width 0.05) (type solid)) (layer "F.CrtYd"))
    (fp_line (start 3.171 1.753) (end -3.179 1.753)
      (stroke (width 0.05) (type solid)) (layer "F.CrtYd"))
    (fp_line (start 3.171 1.753) (end 3.171 -1.747)
      (stroke (width 0.05) (type solid)) (layer "F.CrtYd"))
    (fp_line (start -1.45 -1.101) (end -1.45 1.449)
      (stroke (width 0.15) (type solid)) (layer "F.Fab"))
    (fp_line (start -1.099 -1.451) (end -1.45 -1.101)
      (stroke (width 0.15) (type solid)) (layer "F.Fab"))
    (fp_line (start 1.45 -1.451) (end -1.099 -1.451)
      (stroke (width 0.15) (type solid)) (layer "F.Fab"))
    (fp_line (start 1.45 -1.451) (end 1.45 1.449)
      (stroke (width 0.15) (type solid)) (layer "F.Fab"))
    (fp_line (start 1.45 1.449) (end -1.45 1.449)
      (stroke (width 0.15) (type solid)) (layer "F.Fab"))
    (pad "1" smd roundrect (at -2.199 -0.977 90) (size 0.45 1.45) (layers "F.Cu" "F.Paste" "F.Mask") (roundrect_rratio 0.25)
      (net 410 "/Camera interface/HDA00_CC") (pinfunction "SCL") (pintype "bidirectional"))
    (pad "2" smd roundrect (at -2.199 -0.326 90) (size 0.45 1.45) (layers "F.Cu" "F.Paste" "F.Mask") (roundrect_rratio 0.25)
      (net 225 "/Camera interface/HDA01") (pinfunction "SDA") (pintype "bidirectional"))
    (pad "3" smd roundrect (at -2.199 0.324 90) (size 0.45 1.45) (layers "F.Cu" "F.Paste" "F.Mask") (roundrect_rratio 0.25)
      (net 20 "PL_3V3") (pinfunction "VCC") (pintype "bidirectional"))
    (pad "4" smd roundrect (at -2.199 0.973 90) (size 0.45 1.45) (layers "F.Cu" "F.Paste" "F.Mask") (roundrect_rratio 0.25)
      (net 196 "/Camera interface/CCI0_I2C_SDA_3V3") (pinfunction "SDA_{0}") (pintype "bidirectional"))
    (pad "5" smd roundrect (at 2.201 0.973 90) (size 0.45 1.45) (layers "F.Cu" "F.Paste" "F.Mask") (roundrect_rratio 0.25)
      (net 195 "/Camera interface/CCI0_I2C_SCL_3V3") (pinfunction "SCL_{0}") (pintype "bidirectional"))
    (pad "6" smd roundrect (at 2.201 0.324 90) (size 0.45 1.45) (layers "F.Cu" "F.Paste" "F.Mask") (roundrect_rratio 0.25)
      (net 1 "GND") (pinfunction "GND") (pintype "bidirectional"))
    (pad "7" smd roundrect (at 2.201 -0.326 90) (size 0.45 1.45) (layers "F.Cu" "F.Paste" "F.Mask") (roundrect_rratio 0.25)
      (net 194 "/Camera interface/CCI1_I2C_SDA_3V3") (pinfunction "SDA_{1}") (pintype "bidirectional"))
    (pad "8" smd roundrect (at 2.201 -0.977 90) (size 0.45 1.45) (layers "F.Cu" "F.Paste" "F.Mask") (roundrect_rratio 0.25)
      (net 193 "/Camera interface/CCI1_I2C_SCL_3V3") (pinfunction "SCL_{1}") (pintype "bidirectional"))
  )
	(footprint "kria-k26-devboard-footprints:C_0402_1005Metric" (layer "F.Cu")
    (at 123.85 74.52 -90)
    (descr "Capacitor SMD 0402")
    (tags "capacitor SMD 0402")
    (property "Author" "Antmicro")
    (property "Dielectric" "X5R")
    (property "License" "Apache-2.0")
    (property "MPN" "GRM155R61H104KE14D")
    (property "Manufacturer" "Murata")
    (property "Sheetfile" "usb.kicad_sch")
    (property "Sheetname" "USB")
    (property "Val" "100n")
    (property "Voltage" "50V")
    (property "ki_description" " ")
    (attr smd)
    (fp_text reference "C64" (at 1.08 -1.315 -90) (layer "F.SilkS")
        (effects (font (size 0.7 0.7) (thickness 0.15)) (justify left bottom))
    )
    (fp_text value "C_100n_0402" (at 0 1.4 -90) (layer "F.Fab") hide
        (effects (font (size 0.7 0.7) (thickness 0.15)) (justify left bottom))
    )
    (fp_text user "License: Apache-2.0" (at -0.932 5.17 -90) (layer "F.Fab") hide
        (effects (font (size 0.7 0.7) (thickness 0.15)) (justify left bottom))
    )
    (fp_text user "${REFERENCE}" (at -0.932 3.168 -90) (layer "F.Fab") hide
        (effects (font (size 0.7 0.7) (thickness 0.15)) (justify left bottom))
    )
    (fp_text user "Author: Antmicro" (at -0.932 4.17 -90) (layer "F.Fab") hide
        (effects (font (size 0.7 0.7) (thickness 0.15)) (justify left bottom))
    )
    (fp_rect (start -0.94 -0.47) (end 0.94 0.47)
      (stroke (width 0.05) (type solid)) (fill none) (layer "F.CrtYd"))
    (fp_rect (start -0.499 -0.249) (end 0.499 0.249)
      (stroke (width 0.15) (type solid)) (fill none) (layer "F.Fab"))
    (pad "1" smd roundrect (at -0.484 0 270) (size 0.59 0.64) (layers "F.Cu" "F.Paste" "F.Mask") (roundrect_rratio 0.25)
      (net 306 "USB_5V") (pintype "passive"))
    (pad "2" smd roundrect (at 0.484 0 270) (size 0.59 0.64) (layers "F.Cu" "F.Paste" "F.Mask") (roundrect_rratio 0.25)
      (net 1 "GND") (pintype "passive"))
  )
	(footprint "kria-k26-devboard-footprints:Spacer_Drill4.45mm_H5mm_9774050960R" (layer "F.Cu")
    (at 89.556999 90.7935)
    (property "Author" "Antmicro")
    (property "License" "Apache-2.0")
    (property "MPN" "9774050960R")
    (property "Manufacturer" "Würth Elektronik")
    (property "Sheetfile" "k26_som.kicad_sch")
    (property "Sheetname" "Xilinx K26 SOM")
    (property "ki_description" "Spacer, SMT, Non Stop, Steel, Swage Round, 6 mm x 5 mm, 3.3 mm Internal, WA-SMST Series")
    (property "ki_keywords" "SPACER")
    (clearance 0.6)
    (attr smd)
    (fp_text reference "SP4" (at 0 -3.4) (layer "F.SilkS")
        (effects (font (size 0.7 0.7) (thickness 0.15)) (justify left bottom))
    )
    (fp_text value "Spacer_Drill4.45mm_H5mm_9774050960R" (at 0 4.2) (layer "F.Fab")
        (effects (font (size 0.7 0.7) (thickness 0.15)) (justify left bottom))
    )
    (fp_text user "Author: Antmicro" (at -3.25 8.6) (layer "F.Fab") hide
        (effects (font (size 0.7 0.7) (thickness 0.15)) (justify left bottom))
    )
    (fp_text user "${REFERENCE}" (at -3.25 7.4) (layer "F.Fab") hide
        (effects (font (size 0.7 0.7) (thickness 0.15)) (justify left bottom))
    )
    (fp_text user "License: Apache-2.0" (at -3.25 6.2) (layer "F.Fab") hide
        (effects (font (size 0.7 0.7) (thickness 0.15)) (justify left bottom))
    )
    (fp_circle (center 0 0) (end 3.25 0)
      (stroke (width 0.05) (type solid)) (fill none) (layer "F.CrtYd"))
    (fp_circle (center 0 0) (end 2.564 0)
      (stroke (width 0.15) (type solid)) (fill none) (layer "F.Fab"))
    (pad "1" thru_hole circle (at 0 0) (size 6 6) (drill 4.45) (layers "*.Cu" "*.Mask" "F.Paste")
      (net 1 "GND") (pintype "passive") (solder_paste_margin_ratio -0.05))
  )
	(footprint "kria-k26-devboard-footprints:FB_0402_1005Metric" (layer "F.Cu")
    (at 145.2 112.3)
    (descr "Ferrite Bead SMD 0402")
    (tags "ferrite bead SMD 0402")
    (property "Author" "Antmicro")
    (property "License" "Apache-2.0")
    (property "MPN" "BLM15PD121SN1D")
    (property "Manufacturer" "Murata")
    (property "Sheetfile" "debug.kicad_sch")
    (property "Sheetname" "Debug and JTAG")
    (attr smd)
    (fp_text reference "FB3" (at -1.12 1.21) (layer "F.SilkS")
        (effects (font (size 0.7 0.7) (thickness 0.15)) (justify left bottom))
    )
    (fp_text value "FB_120Z_1.3A_0402" (at 0 1.4) (layer "F.Fab") hide
        (effects (font (size 0.7 0.7) (thickness 0.15)) (justify left bottom))
    )
    (fp_text user "${REFERENCE}" (at -0.95 3.168) (layer "F.Fab") hide
        (effects (font (size 0.7 0.7) (thickness 0.15)) (justify left bottom))
    )
    (fp_text user "License: Apache-2.0" (at -0.95 5.169) (layer "F.Fab") hide
        (effects (font (size 0.7 0.7) (thickness 0.15)) (justify left bottom))
    )
    (fp_text user "Author: Antmicro" (at -0.95 4.169) (layer "F.Fab") hide
        (effects (font (size 0.7 0.7) (thickness 0.15)) (justify left bottom))
    )
    (fp_rect (start -0.95 -0.48) (end 0.95 0.48)
      (stroke (width 0.05) (type solid)) (fill none) (layer "F.CrtYd"))
    (fp_rect (start -0.5 -0.25) (end 0.5 0.25)
      (stroke (width 0.15) (type solid)) (fill none) (layer "F.Fab"))
    (pad "1" smd roundrect (at -0.485 0) (size 0.59 0.64) (layers "F.Cu" "F.Paste" "F.Mask") (roundrect_rratio 0.25)
      (net 187 "/Debug and JTAG/PD_3V3") (pintype "passive"))
    (pad "2" smd roundrect (at 0.485 0) (size 0.59 0.64) (layers "F.Cu" "F.Paste" "F.Mask") (roundrect_rratio 0.25)
      (net 133 "/Debug and JTAG/VCC_PD") (pintype "passive"))
  )
	(footprint "kria-k26-devboard-footprints:R_0402_1005Metric" (layer "F.Cu")
    (at 147.225 110 -90)
    (descr "Resistor SMD 0402")
    (tags "resistor SMD 0402")
    (property "Author" "Antmicro")
    (property "Current" "1A")
    (property "DNP" "DNP")
    (property "License" "Apache-2.0")
    (property "MPN" "ERJ2GE0R00X")
    (property "Manufacturer" "Panasonic")
    (property "Sheetfile" "debug.kicad_sch")
    (property "Sheetname" "Debug and JTAG")
    (property "Tolerance" "")
    (property "Val" "0R")
    (property "dnp" "")
    (property "exclude_from_bom" "")
    (property "ki_description" "0R resistor in 0402 package with unspecified tolerance")
    (attr exclude_from_pos_files exclude_from_bom)
    (fp_text reference "R100" (at -3.22 -0.365 -90) (layer "F.SilkS")
        (effects (font (size 0.7 0.7) (thickness 0.15)) (justify left bottom))
    )
    (fp_text value "R_0R_0402" (at 0 1.4 -90) (layer "F.Fab") hide
        (effects (font (size 0.7 0.7) (thickness 0.15)) (justify left bottom))
    )
    (fp_text user "License: Apache-2.0" (at -0.95 5.169 -90) (layer "F.Fab") hide
        (effects (font (size 0.7 0.7) (thickness 0.15)) (justify left bottom))
    )
    (fp_text user "Author: Antmicro" (at -0.95 4.169 -90) (layer "F.Fab") hide
        (effects (font (size 0.7 0.7) (thickness 0.15)) (justify left bottom))
    )
    (fp_text user "${REFERENCE}" (at -0.95 3.168 -90) (layer "F.Fab") hide
        (effects (font (size 0.7 0.7) (thickness 0.15)) (justify left bottom))
    )
    (fp_rect (start -0.93 -0.47) (end 0.93 0.47)
      (stroke (width 0.05) (type solid)) (fill none) (layer "F.CrtYd"))
    (fp_rect (start -0.5 -0.25) (end 0.5 0.25)
      (stroke (width 0.15) (type solid)) (fill none) (layer "F.Fab"))
    (pad "1" smd roundrect (at -0.485 0 270) (size 0.59 0.64) (layers "F.Cu" "F.Paste" "F.Mask") (roundrect_rratio 0.25)
      (net 233 "/Debug and JTAG/USB_P") (pintype "passive"))
    (pad "2" smd roundrect (at 0.485 0 270) (size 0.59 0.64) (layers "F.Cu" "F.Paste" "F.Mask") (roundrect_rratio 0.25)
      (net 222 "/Debug and JTAG/USBB_P") (pintype "passive"))
  )
	(footprint "kria-k26-devboard-footprints:R_0402_1005Metric" (layer "F.Cu")
    (at 147.225 107.6 -90)
    (descr "Resistor SMD 0402")
    (tags "resistor SMD 0402")
    (property "Author" "Antmicro")
    (property "Current" "1A")
    (property "License" "Apache-2.0")
    (property "MPN" "ERJ2GE0R00X")
    (property "Manufacturer" "Panasonic")
    (property "Sheetfile" "debug.kicad_sch")
    (property "Sheetname" "Debug and JTAG")
    (property "Tolerance" "")
    (property "Val" "0R")
    (property "ki_description" "0R resistor in 0402 package with unspecified tolerance")
    (attr smd)
    (fp_text reference "R97" (at -3.74 -0.395 -90) (layer "F.SilkS")
        (effects (font (size 0.7 0.7) (thickness 0.15)) (justify left bottom))
    )
    (fp_text value "R_0R_0402" (at 0 1.4 -90) (layer "F.Fab") hide
        (effects (font (size 0.7 0.7) (thickness 0.15)) (justify left bottom))
    )
    (fp_text user "${REFERENCE}" (at -0.95 3.168 -90) (layer "F.Fab") hide
        (effects (font (size 0.7 0.7) (thickness 0.15)) (justify left bottom))
    )
    (fp_text user "License: Apache-2.0" (at -0.95 5.169 -90) (layer "F.Fab") hide
        (effects (font (size 0.7 0.7) (thickness 0.15)) (justify left bottom))
    )
    (fp_text user "Author: Antmicro" (at -0.95 4.169 -90) (layer "F.Fab") hide
        (effects (font (size 0.7 0.7) (thickness 0.15)) (justify left bottom))
    )
    (fp_rect (start -0.93 -0.47) (end 0.93 0.47)
      (stroke (width 0.05) (type solid)) (fill none) (layer "F.CrtYd"))
    (fp_rect (start -0.5 -0.25) (end 0.5 0.25)
      (stroke (width 0.15) (type solid)) (fill none) (layer "F.Fab"))
    (pad "1" smd roundrect (at -0.485 0 270) (size 0.59 0.64) (layers "F.Cu" "F.Paste" "F.Mask") (roundrect_rratio 0.25)
      (net 188 "/Debug and JTAG/USBC_P") (pintype "passive"))
    (pad "2" smd roundrect (at 0.485 0 270) (size 0.59 0.64) (layers "F.Cu" "F.Paste" "F.Mask") (roundrect_rratio 0.25)
      (net 233 "/Debug and JTAG/USB_P") (pintype "passive"))
  )
	(footprint "kria-k26-devboard-footprints:R_0402_1005Metric" (layer "F.Cu")
    (at 148.225 107.6 -90)
    (descr "Resistor SMD 0402")
    (tags "resistor SMD 0402")
    (property "Author" "Antmicro")
    (property "Current" "1A")
    (property "License" "Apache-2.0")
    (property "MPN" "ERJ2GE0R00X")
    (property "Manufacturer" "Panasonic")
    (property "Sheetfile" "debug.kicad_sch")
    (property "Sheetname" "Debug and JTAG")
    (property "Tolerance" "")
    (property "Val" "0R")
    (property "ki_description" "0R resistor in 0402 package with unspecified tolerance")
    (attr smd)
    (fp_text reference "R98" (at -3.74 -0.395 -90) (layer "F.SilkS")
        (effects (font (size 0.7 0.7) (thickness 0.15)) (justify left bottom))
    )
    (fp_text value "R_0R_0402" (at 0 1.4 -90) (layer "F.Fab") hide
        (effects (font (size 0.7 0.7) (thickness 0.15)) (justify left bottom))
    )
    (fp_text user "License: Apache-2.0" (at -0.95 5.169 -90) (layer "F.Fab") hide
        (effects (font (size 0.7 0.7) (thickness 0.15)) (justify left bottom))
    )
    (fp_text user "${REFERENCE}" (at -0.95 3.168 -90) (layer "F.Fab") hide
        (effects (font (size 0.7 0.7) (thickness 0.15)) (justify left bottom))
    )
    (fp_text user "Author: Antmicro" (at -0.95 4.169 -90) (layer "F.Fab") hide
        (effects (font (size 0.7 0.7) (thickness 0.15)) (justify left bottom))
    )
    (fp_rect (start -0.93 -0.47) (end 0.93 0.47)
      (stroke (width 0.05) (type solid)) (fill none) (layer "F.CrtYd"))
    (fp_rect (start -0.5 -0.25) (end 0.5 0.25)
      (stroke (width 0.15) (type solid)) (fill none) (layer "F.Fab"))
    (pad "1" smd roundrect (at -0.485 0 270) (size 0.59 0.64) (layers "F.Cu" "F.Paste" "F.Mask") (roundrect_rratio 0.25)
      (net 189 "/Debug and JTAG/USBC_N") (pintype "passive"))
    (pad "2" smd roundrect (at 0.485 0 270) (size 0.59 0.64) (layers "F.Cu" "F.Paste" "F.Mask") (roundrect_rratio 0.25)
      (net 234 "/Debug and JTAG/USB_N") (pintype "passive"))
  )
	(footprint "kria-k26-devboard-footprints:C_0402_1005Metric" (layer "F.Cu")
    (at 152.925 124.99 -90)
    (descr "Capacitor SMD 0402")
    (tags "capacitor SMD 0402")
    (property "Author" "Antmicro")
    (property "Dielectric" "")
    (property "License" "Apache-2.0")
    (property "MPN" "MC0402N180J500CT")
    (property "Manufacturer" "Multicomp")
    (property "Sheetfile" "debug.kicad_sch")
    (property "Sheetname" "Debug and JTAG")
    (property "Val" "18p")
    (property "Voltage" "")
    (property "ki_description" " ")
    (attr smd)
    (fp_text reference "C156" (at 3.74 -0.415 -90) (layer "F.SilkS")
        (effects (font (size 0.7 0.7) (thickness 0.15)) (justify left bottom))
    )
    (fp_text value "C_18p_0402" (at 0 1.4 -90) (layer "F.Fab") hide
        (effects (font (size 0.7 0.7) (thickness 0.15)) (justify left bottom))
    )
    (fp_text user "License: Apache-2.0" (at -0.932 5.17 -90) (layer "F.Fab") hide
        (effects (font (size 0.7 0.7) (thickness 0.15)) (justify left bottom))
    )
    (fp_text user "Author: Antmicro" (at -0.932 4.17 -90) (layer "F.Fab") hide
        (effects (font (size 0.7 0.7) (thickness 0.15)) (justify left bottom))
    )
    (fp_text user "${REFERENCE}" (at -0.932 3.168 -90) (layer "F.Fab") hide
        (effects (font (size 0.7 0.7) (thickness 0.15)) (justify left bottom))
    )
    (fp_rect (start -0.94 -0.47) (end 0.94 0.47)
      (stroke (width 0.05) (type solid)) (fill none) (layer "F.CrtYd"))
    (fp_rect (start -0.499 -0.249) (end 0.499 0.249)
      (stroke (width 0.15) (type solid)) (fill none) (layer "F.Fab"))
    (pad "1" smd roundrect (at -0.484 0 270) (size 0.59 0.64) (layers "F.Cu" "F.Paste" "F.Mask") (roundrect_rratio 0.25)
      (net 139 "/Debug and JTAG/XOUT") (pintype "passive"))
    (pad "2" smd roundrect (at 0.484 0 270) (size 0.59 0.64) (layers "F.Cu" "F.Paste" "F.Mask") (roundrect_rratio 0.25)
      (net 1 "GND") (pintype "passive"))
  )
)
